# T6G (Grand Teton) — schematic netlist excerpt (pin names and nets, part order shuffled) for the footprints in the layout excerpt that follows; sources: Cadence DE-HDL packaged netlist, KiCad conversion of 04192023_DAF0TMB3IC0_F0TG_MB_C_brd_V02_OCP.brd

C5234  Q_CAP  0.1UF 25V 10% EMPTY  pkg C0402  page 234 : A = P3V3_AUX ; B = GND
C125  Q_CAP  1UF 4V 20% X6S  pkg 0201  page 323 : A = P1V8_CPU1_RT0_1A_1D ; B = GND
C1034  Q_CAP  4.7UF 6.3V 20% X6S  pkg 0402  page 312 : A = P0V9_CPU0_RT3_2A ; B = GND

(kicad_pcb
	(version 20260206)
	(generator "pcbnew")
	(generator_version "10.0")
	(general
		(thickness 1.6)
		(legacy_teardrops no)
	)
	(paper "A4")
	(title_block
		(title "04192023_DAF0TMB3IC0_F0TG_MB_C_brd_V02_OCP.brd")
		(comment 1 "Grand Teton / footprints 5694-5696 of 8354")
	)
	(layers
		(0 "F.Cu" signal "TOP")
		(4 "In1.Cu" signal "GND")
		(6 "In2.Cu" signal "IN1")
		(8 "In3.Cu" signal "GND1")
		(10 "In4.Cu" signal "IN2")
		(12 "In5.Cu" signal "GND2")
		(14 "In6.Cu" signal "IN3")
		(16 "In7.Cu" signal "GND3")
		(18 "In8.Cu" signal "VCC")
		(20 "In9.Cu" signal "VCC1")
		(22 "In10.Cu" signal "GND4")
		(24 "In11.Cu" signal "IN4")
		(26 "In12.Cu" signal "GND5")
		(28 "In13.Cu" signal "IN5")
		(30 "In14.Cu" signal "GND6")
		(32 "In15.Cu" signal "IN6")
		(34 "In16.Cu" signal "GND7")
		(2 "B.Cu" signal "BOTTOM")
		(9 "F.Adhes" user "F.Adhesive")
		(11 "B.Adhes" user "B.Adhesive")
		(13 "F.Paste" user "Package Geometry/Pastemask Top")
		(15 "B.Paste" user "Package Geometry/Pastemask Bottom")
		(5 "F.SilkS" user "Ref Des/Silkscreen Top")
		(7 "B.SilkS" user "Ref Des/Silkscreen Bottom")
		(1 "F.Mask" user "Board Geometry/Soldermask Top")
		(3 "B.Mask" user "Board Geometry/Soldermask Bottom")
		(17 "Dwgs.User" user "User.Drawings")
		(19 "Cmts.User" user "User.Comments")
		(21 "Eco1.User" user "User.Eco1")
		(23 "Eco2.User" user "User.Eco2")
		(25 "Edge.Cuts" user "Board Geometry/Outline")
		(27 "Margin" user)
		(31 "F.CrtYd" user "Package Geometry/Place Bound Top")
		(29 "B.CrtYd" user "Package Geometry/Place Bound Bottom")
		(35 "F.Fab" user "Ref Des/Assembly Top")
		(33 "B.Fab" user "Ref Des/Assembly Bottom")
	)
	(footprint ""
		(layer "B.Cu")
		(at 383.69113 -398.942052 90)
		(property "Reference" "C1034"
			(at 0 0 90)
			(layer "B.SilkS")
			(hide yes)
			(effects
				(font
					(size 1.27 1.27)
				)
				(justify mirror)
			)
		)
		(property "Value" ""
			(at 0 0 90)
			(layer "B.Fab")
			(effects
				(font
					(size 1.27 1.27)
				)
				(justify mirror)
			)
		)
		(duplicate_pad_numbers_are_jumpers no)
		(fp_line
			(start 0.7874 -0.4064)
			(end -0.7874 -0.4064)
			(stroke
				(width 0.1524)
				(type default)
			)
			(layer "B.SilkS")
		)
		(fp_line
			(start -0.7874 -0.4064)
			(end -0.7874 0.4064)
			(stroke
				(width 0.1524)
				(type default)
			)
			(layer "B.SilkS")
		)
		(fp_line
			(start 0.7874 0.4064)
			(end 0.7874 -0.4064)
			(stroke
				(width 0.1524)
				(type default)
			)
			(layer "B.SilkS")
		)
		(fp_line
			(start -0.7874 0.4064)
			(end 0.7874 0.4064)
			(stroke
				(width 0.1524)
				(type default)
			)
			(layer "B.SilkS")
		)
		(fp_line
			(start 0.67945 -0.305054)
			(end 0.12065 -0.305054)
			(stroke
				(width 0.1)
				(type default)
			)
			(layer "B.Fab")
		)
		(fp_line
			(start 0.12065 -0.305054)
			(end 0.12065 -0.2794)
			(stroke
				(width 0.1)
				(type default)
			)
			(layer "B.Fab")
		)
		(fp_line
			(start -0.12065 -0.3048)
			(end -0.67945 -0.3048)
			(stroke
				(width 0.1)
				(type default)
			)
			(layer "B.Fab")
		)
		(fp_line
			(start -0.67945 -0.3048)
			(end -0.67945 0.3048)
			(stroke
				(width 0.1)
				(type default)
			)
			(layer "B.Fab")
		)
		(fp_line
			(start 0.12065 -0.2794)
			(end -0.12065 -0.2794)
			(stroke
				(width 0.1)
				(type default)
			)
			(layer "B.Fab")
		)
		(fp_line
			(start -0.12065 -0.2794)
			(end -0.12065 -0.3048)
			(stroke
				(width 0.1)
				(type default)
			)
			(layer "B.Fab")
		)
		(fp_line
			(start 0.12065 0.2794)
			(end 0.12065 0.3048)
			(stroke
				(width 0.1)
				(type default)
			)
			(layer "B.Fab")
		)
		(fp_line
			(start -0.120396 0.2794)
			(end 0.12065 0.2794)
			(stroke
				(width 0.1)
				(type default)
			)
			(layer "B.Fab")
		)
		(fp_line
			(start 0.67945 0.3048)
			(end 0.67945 -0.305054)
			(stroke
				(width 0.1)
				(type default)
			)
			(layer "B.Fab")
		)
		(fp_line
			(start 0.12065 0.3048)
			(end 0.67945 0.3048)
			(stroke
				(width 0.1)
				(type default)
			)
			(layer "B.Fab")
		)
		(fp_line
			(start -0.120396 0.3048)
			(end -0.120396 0.2794)
			(stroke
				(width 0.1)
				(type default)
			)
			(layer "B.Fab")
		)
		(fp_line
			(start -0.67945 0.3048)
			(end -0.120396 0.3048)
			(stroke
				(width 0.1)
				(type default)
			)
			(layer "B.Fab")
		)
		(pad "1" smd circle
			(at 0.40005 0 270)
			(size 0 0)
			(layers "B.Cu" "B.Mask" "B.Paste")
			(net "P0V9_CPU0_RT3_2A")
		)
		(pad "2" smd circle
			(at -0.40005 0 270)
			(size 0 0)
			(layers "B.Cu" "B.Mask" "B.Paste")
			(net "GND")
		)
	)
	(footprint ""
		(layer "B.Cu")
		(at 58.178446 -386.766562 90)
		(property "Reference" "C125"
			(at 0 0 90)
			(layer "B.SilkS")
			(hide yes)
			(effects
				(font
					(size 1.27 1.27)
				)
				(justify mirror)
			)
		)
		(property "Value" ""
			(at 0 0 90)
			(layer "B.Fab")
			(effects
				(font
					(size 1.27 1.27)
				)
				(justify mirror)
			)
		)
		(duplicate_pad_numbers_are_jumpers no)
		(fp_line
			(start 0.299974 -0.150114)
			(end -0.299974 -0.150114)
			(stroke
				(width 0.1)
				(type default)
			)
			(layer "B.Fab")
		)
		(fp_line
			(start -0.299974 -0.150114)
			(end -0.299974 0.150114)
			(stroke
				(width 0.1)
				(type default)
			)
			(layer "B.Fab")
		)
		(fp_line
			(start 0.299974 0.150114)
			(end 0.299974 -0.150114)
			(stroke
				(width 0.1)
				(type default)
			)
			(layer "B.Fab")
		)
		(fp_line
			(start -0.299974 0.150114)
			(end 0.299974 0.150114)
			(stroke
				(width 0.1)
				(type default)
			)
			(layer "B.Fab")
		)
		(pad "1" smd rect
			(at 0.2667 0 270)
			(size 0.3048 0.381)
			(layers "B.Cu" "B.Mask" "B.Paste")
			(net "P1V8_CPU1_RT0_1A_1D")
		)
		(pad "2" smd rect
			(at -0.2667 0 270)
			(size 0.3048 0.381)
			(layers "B.Cu" "B.Mask" "B.Paste")
			(net "GND")
		)
	)
	(footprint ""
		(layer "B.Cu")
		(at 15.433294 -110.987586 90)
		(property "Reference" "C5234"
			(at 0 0 90)
			(layer "B.SilkS")
			(hide yes)
			(effects
				(font
					(size 1.27 1.27)
				)
				(justify mirror)
			)
		)
		(property "Value" ""
			(at 0 0 90)
			(layer "B.Fab")
			(effects
				(font
					(size 1.27 1.27)
				)
				(justify mirror)
			)
		)
		(duplicate_pad_numbers_are_jumpers no)
		(fp_line
			(start 0.7874 -0.4064)
			(end -0.7874 -0.4064)
			(stroke
				(width 0.1524)
				(type default)
			)
			(layer "B.SilkS")
		)
		(fp_line
			(start -0.7874 -0.4064)
			(end -0.7874 0.4064)
			(stroke
				(width 0.1524)
				(type default)
			)
			(layer "B.SilkS")
		)
		(fp_line
			(start 0.7874 0.4064)
			(end 0.7874 -0.4064)
			(stroke
				(width 0.1524)
				(type default)
			)
			(layer "B.SilkS")
		)
		(fp_line
			(start -0.7874 0.4064)
			(end 0.7874 0.4064)
			(stroke
				(width 0.1524)
				(type default)
			)
			(layer "B.SilkS")
		)
		(fp_line
			(start 0.67945 -0.305054)
			(end 0.12065 -0.305054)
			(stroke
				(width 0.1)
				(type default)
			)
			(layer "B.Fab")
		)
		(fp_line
			(start 0.12065 -0.305054)
			(end 0.12065 -0.2794)
			(stroke
				(width 0.1)
				(type default)
			)
			(layer "B.Fab")
		)
		(fp_line
			(start -0.12065 -0.3048)
			(end -0.67945 -0.3048)
			(stroke
				(width 0.1)
				(type default)
			)
			(layer "B.Fab")
		)
		(fp_line
			(start -0.67945 -0.3048)
			(end -0.67945 0.3048)
			(stroke
				(width 0.1)
				(type default)
			)
			(layer "B.Fab")
		)
		(fp_line
			(start 0.12065 -0.2794)
			(end -0.12065 -0.2794)
			(stroke
				(width 0.1)
				(type default)
			)
			(layer "B.Fab")
		)
		(fp_line
			(start -0.12065 -0.2794)
			(end -0.12065 -0.3048)
			(stroke
				(width 0.1)
				(type default)
			)
			(layer "B.Fab")
		)
		(fp_line
			(start 0.12065 0.2794)
			(end 0.12065 0.3048)
			(stroke
				(width 0.1)
				(type default)
			)
			(layer "B.Fab")
		)
		(fp_line
			(start -0.120396 0.2794)
			(end 0.12065 0.2794)
			(stroke
				(width 0.1)
				(type default)
			)
			(layer "B.Fab")
		)
		(fp_line
			(start 0.67945 0.3048)
			(end 0.67945 -0.305054)
			(stroke
				(width 0.1)
				(type default)
			)
			(layer "B.Fab")
		)
		(fp_line
			(start 0.12065 0.3048)
			(end 0.67945 0.3048)
			(stroke
				(width 0.1)
				(type default)
			)
			(layer "B.Fab")
		)
		(fp_line
			(start -0.120396 0.3048)
			(end -0.120396 0.2794)
			(stroke
				(width 0.1)
				(type default)
			)
			(layer "B.Fab")
		)
		(fp_line
			(start -0.67945 0.3048)
			(end -0.120396 0.3048)
			(stroke
				(width 0.1)
				(type default)
			)
			(layer "B.Fab")
		)
		(pad "1" smd circle
			(at 0.40005 0 270)
			(size 0 0)
			(layers "B.Cu" "B.Mask" "B.Paste")
			(net "P3V3_AUX")
		)
		(pad "2" smd circle
			(at -0.40005 0 270)
			(size 0 0)
			(layers "B.Cu" "B.Mask" "B.Paste")
			(net "GND")
		)
	)
)
